(kicad_pcb
	(version 20260206)
	(generator "pcbnew")
	(generator_version "10.0")
	(general
		(thickness 1.6)
		(legacy_teardrops no)
	)
	(paper "A4")
	(title_block
		(title "04192023_DAF0TMB3IC0_F0TG_MB_C_brd_V02_OCP.brd")
		(comment 1 "Grand Teton / footprint 3955 of 8354 (U25), pads 3334-3443 of 6102")
	)
	(layers
		(0 "F.Cu" signal "TOP")
		(4 "In1.Cu" signal "GND")
		(6 "In2.Cu" signal "IN1")
		(8 "In3.Cu" signal "GND1")
		(10 "In4.Cu" signal "IN2")
		(12 "In5.Cu" signal "GND2")
		(14 "In6.Cu" signal "IN3")
		(16 "In7.Cu" signal "GND3")
		(18 "In8.Cu" signal "VCC")
		(20 "In9.Cu" signal "VCC1")
		(22 "In10.Cu" signal "GND4")
		(24 "In11.Cu" signal "IN4")
		(26 "In12.Cu" signal "GND5")
		(28 "In13.Cu" signal "IN5")
		(30 "In14.Cu" signal "GND6")
		(32 "In15.Cu" signal "IN6")
		(34 "In16.Cu" signal "GND7")
		(2 "B.Cu" signal "BOTTOM")
		(9 "F.Adhes" user "F.Adhesive")
		(11 "B.Adhes" user "B.Adhesive")
		(13 "F.Paste" user "Package Geometry/Pastemask Top")
		(15 "B.Paste" user "Package Geometry/Pastemask Bottom")
		(5 "F.SilkS" user "Ref Des/Silkscreen Top")
		(7 "B.SilkS" user "Ref Des/Silkscreen Bottom")
		(1 "F.Mask" user "Board Geometry/Soldermask Top")
		(3 "B.Mask" user "Board Geometry/Soldermask Bottom")
		(17 "Dwgs.User" user "User.Drawings")
		(19 "Cmts.User" user "User.Comments")
		(21 "Eco1.User" user "User.Eco1")
		(23 "Eco2.User" user "User.Eco2")
		(25 "Edge.Cuts" user "Board Geometry/Outline")
		(27 "Margin" user)
		(31 "F.CrtYd" user "Package Geometry/Place Bound Top")
		(29 "B.CrtYd" user "Package Geometry/Place Bound Bottom")
		(35 "F.Fab" user "Ref Des/Assembly Top")
		(33 "B.Fab" user "Ref Des/Assembly Bottom")
	)
	(footprint ""
		(layer "F.Cu")
		(at 359.867962 -258.880102 180)
		(property "Reference" "U25"
			(at -45.78477 -62.086744 0)
			(unlocked yes)
			(layer "F.SilkS")
			(effects
				(font
					(size 0.7874 0.5842)
					(thickness 0.1524)
				)
			)
		)
		(property "Value" ""
			(at 0 0 180)
			(layer "F.Fab")
			(effects
				(font
					(size 1.27 1.27)
				)
			)
		)
		(duplicate_pad_numbers_are_jumpers no)
		(pad "CH23" smd circle
			(at -14.249908 19.800062 180)
			(size 0.450088 0.450088)
			(layers "F.Cu" "F.Mask" "F.Paste")
			(net "PVDDCR_CPU1_P0")
		)
		(pad "CH24" smd circle
			(at -13.310108 19.800062 180)
			(size 0.450088 0.450088)
			(layers "F.Cu" "F.Mask" "F.Paste")
			(net "PVDDCR_CPU1_P0")
		)
		(pad "CH25" smd circle
			(at -12.370054 19.800062 180)
			(size 0.450088 0.450088)
			(layers "F.Cu" "F.Mask" "F.Paste")
			(net "GND")
		)
		(pad "CH26" smd circle
			(at -11.43 19.800062 180)
			(size 0.450088 0.450088)
			(layers "F.Cu" "F.Mask" "F.Paste")
			(net "PVDDCR_CPU1_P0")
		)
		(pad "CH27" smd circle
			(at -10.489946 19.800062 180)
			(size 0.450088 0.450088)
			(layers "F.Cu" "F.Mask" "F.Paste")
			(net "PVDDCR_CPU1_P0")
		)
		(pad "CH28" smd circle
			(at -9.549892 19.800062 180)
			(size 0.450088 0.450088)
			(layers "F.Cu" "F.Mask" "F.Paste")
			(net "GND")
		)
		(pad "CH29" smd circle
			(at -8.610092 19.800062 180)
			(size 0.450088 0.450088)
			(layers "F.Cu" "F.Mask" "F.Paste")
			(net "PVDDCR_CPU1_P0")
		)
		(pad "CH30" smd circle
			(at -7.670038 19.800062 180)
			(size 0.450088 0.450088)
			(layers "F.Cu" "F.Mask" "F.Paste")
			(net "PVDDCR_CPU1_P0")
		)
		(pad "CH31" smd circle
			(at -6.729984 19.800062 180)
			(size 0.450088 0.450088)
			(layers "F.Cu" "F.Mask" "F.Paste")
			(net "GND")
		)
		(pad "CH32" smd circle
			(at -5.78993 19.800062 180)
			(size 0.450088 0.450088)
			(layers "F.Cu" "F.Mask" "F.Paste")
			(net "PVDDCR_CPU1_P0")
		)
		(pad "CH33" smd circle
			(at -4.849876 19.800062 180)
			(size 0.450088 0.450088)
			(layers "F.Cu" "F.Mask" "F.Paste")
			(net "PVDDCR_CPU1_P0")
		)
		(pad "CH34" smd circle
			(at -3.910076 19.800062 180)
			(size 0.450088 0.450088)
			(layers "F.Cu" "F.Mask" "F.Paste")
			(net "GND")
		)
		(pad "CH35" smd circle
			(at -2.970022 19.800062 180)
			(size 0.450088 0.450088)
			(layers "F.Cu" "F.Mask" "F.Paste")
			(net "P5E_CPU0_P3_TX_DN<2>")
		)
		(pad "CH36" smd circle
			(at -2.029968 19.800062 180)
			(size 0.450088 0.450088)
			(layers "F.Cu" "F.Mask" "F.Paste")
			(net "P5E_CPU0_P3_TX_DP<2>")
		)
		(pad "CH37" smd circle
			(at -1.089914 19.800062 180)
			(size 0.450088 0.450088)
			(layers "F.Cu" "F.Mask" "F.Paste")
			(net "GND")
		)
		(pad "CH39" smd circle
			(at 0.78994 19.800062 180)
			(size 0.450088 0.450088)
			(layers "F.Cu" "F.Mask" "F.Paste")
			(net "GND")
		)
		(pad "CH40" smd circle
			(at 1.729994 19.800062 180)
			(size 0.450088 0.450088)
			(layers "F.Cu" "F.Mask" "F.Paste")
			(net "P5E_CPU0_P1_RX_DP<13>")
		)
		(pad "CH41" smd circle
			(at 2.670048 19.800062 180)
			(size 0.450088 0.450088)
			(layers "F.Cu" "F.Mask" "F.Paste")
			(net "P5E_CPU0_P1_RX_DN<13>")
		)
		(pad "CH42" smd circle
			(at 3.610102 19.800062 180)
			(size 0.450088 0.450088)
			(layers "F.Cu" "F.Mask" "F.Paste")
			(net "GND")
		)
		(pad "CH43" smd circle
			(at 4.549902 19.800062 180)
			(size 0.450088 0.450088)
			(layers "F.Cu" "F.Mask" "F.Paste")
			(net "PVDDCR_CPU1_P0")
		)
		(pad "CH44" smd circle
			(at 5.489956 19.800062 180)
			(size 0.450088 0.450088)
			(layers "F.Cu" "F.Mask" "F.Paste")
			(net "PVDDCR_CPU1_P0")
		)
		(pad "CH45" smd circle
			(at 6.43001 19.800062 180)
			(size 0.450088 0.450088)
			(layers "F.Cu" "F.Mask" "F.Paste")
			(net "GND")
		)
		(pad "CH46" smd circle
			(at 7.370064 19.800062 180)
			(size 0.450088 0.450088)
			(layers "F.Cu" "F.Mask" "F.Paste")
			(net "PVDDCR_CPU1_P0")
		)
		(pad "CH47" smd circle
			(at 8.310118 19.800062 180)
			(size 0.450088 0.450088)
			(layers "F.Cu" "F.Mask" "F.Paste")
			(net "PVDDCR_CPU1_P0")
		)
		(pad "CH48" smd circle
			(at 9.249918 19.800062 180)
			(size 0.450088 0.450088)
			(layers "F.Cu" "F.Mask" "F.Paste")
			(net "GND")
		)
		(pad "CH49" smd circle
			(at 10.189972 19.800062 180)
			(size 0.450088 0.450088)
			(layers "F.Cu" "F.Mask" "F.Paste")
			(net "PVDDCR_CPU1_P0")
		)
		(pad "CH50" smd circle
			(at 11.130026 19.800062 180)
			(size 0.450088 0.450088)
			(layers "F.Cu" "F.Mask" "F.Paste")
			(net "PVDDCR_CPU1_P0")
		)
		(pad "CH51" smd circle
			(at 12.07008 19.800062 180)
			(size 0.450088 0.450088)
			(layers "F.Cu" "F.Mask" "F.Paste")
			(net "GND")
		)
		(pad "CH52" smd circle
			(at 13.00988 19.800062 180)
			(size 0.450088 0.450088)
			(layers "F.Cu" "F.Mask" "F.Paste")
			(net "PVDDCR_CPU1_P0")
		)
		(pad "CH53" smd circle
			(at 13.949934 19.800062 180)
			(size 0.450088 0.450088)
			(layers "F.Cu" "F.Mask" "F.Paste")
			(net "PVDDCR_CPU1_P0")
		)
		(pad "CH54" smd circle
			(at 14.889988 19.800062 180)
			(size 0.450088 0.450088)
			(layers "F.Cu" "F.Mask" "F.Paste")
			(net "GND")
		)
		(pad "CH55" smd circle
			(at 15.830042 19.800062 180)
			(size 0.450088 0.450088)
			(layers "F.Cu" "F.Mask" "F.Paste")
			(net "M_C_CPU0_SB_DQ<7>")
		)
		(pad "CH56" smd circle
			(at 16.770096 19.800062 180)
			(size 0.450088 0.450088)
			(layers "F.Cu" "F.Mask" "F.Paste")
			(net "M_C_CPU0_SB_DQ<8>")
		)
		(pad "CH57" smd circle
			(at 17.709896 19.800062 180)
			(size 0.450088 0.450088)
			(layers "F.Cu" "F.Mask" "F.Paste")
			(net "GND")
		)
		(pad "CH58" smd circle
			(at 18.64995 19.800062 180)
			(size 0.450088 0.450088)
			(layers "F.Cu" "F.Mask" "F.Paste")
			(net "M_D_CPU0_SB_DQ<7>")
		)
		(pad "CH59" smd circle
			(at 19.590004 19.800062 180)
			(size 0.450088 0.450088)
			(layers "F.Cu" "F.Mask" "F.Paste")
			(net "GND")
		)
		(pad "CH60" smd circle
			(at 20.530058 19.800062 180)
			(size 0.450088 0.450088)
			(layers "F.Cu" "F.Mask" "F.Paste")
			(net "M_D_CPU0_SB_DQ<8>")
		)
		(pad "CH61" smd circle
			(at 21.470112 19.800062 180)
			(size 0.450088 0.450088)
			(layers "F.Cu" "F.Mask" "F.Paste")
			(net "GND")
		)
		(pad "CH62" smd circle
			(at 22.409912 19.800062 180)
			(size 0.450088 0.450088)
			(layers "F.Cu" "F.Mask" "F.Paste")
			(net "M_B_CPU0_SB_DQ<7>")
		)
		(pad "CH63" smd circle
			(at 23.349966 19.800062 180)
			(size 0.450088 0.450088)
			(layers "F.Cu" "F.Mask" "F.Paste")
			(net "M_B_CPU0_SB_DQ<8>")
		)
		(pad "CH64" smd circle
			(at 24.29002 19.800062 180)
			(size 0.450088 0.450088)
			(layers "F.Cu" "F.Mask" "F.Paste")
			(net "GND")
		)
		(pad "CH65" smd circle
			(at 25.230074 19.800062 180)
			(size 0.450088 0.450088)
			(layers "F.Cu" "F.Mask" "F.Paste")
			(net "M_F_CPU0_SB_DQ<7>")
		)
		(pad "CH66" smd circle
			(at 26.170128 19.800062 180)
			(size 0.450088 0.450088)
			(layers "F.Cu" "F.Mask" "F.Paste")
			(net "GND")
		)
		(pad "CH67" smd circle
			(at 27.109928 19.800062 180)
			(size 0.450088 0.450088)
			(layers "F.Cu" "F.Mask" "F.Paste")
			(net "M_F_CPU0_SB_DQ<8>")
		)
		(pad "CH68" smd circle
			(at 28.049982 19.800062 180)
			(size 0.450088 0.450088)
			(layers "F.Cu" "F.Mask" "F.Paste")
			(net "GND")
		)
		(pad "CH69" smd circle
			(at 28.990036 19.800062 180)
			(size 0.450088 0.450088)
			(layers "F.Cu" "F.Mask" "F.Paste")
			(net "M_E_CPU0_SB_DQ<7>")
		)
		(pad "CH70" smd circle
			(at 29.93009 19.800062 180)
			(size 0.450088 0.450088)
			(layers "F.Cu" "F.Mask" "F.Paste")
			(net "M_E_CPU0_SB_DQ<8>")
		)
		(pad "CH71" smd circle
			(at 30.86989 19.800062 180)
			(size 0.450088 0.450088)
			(layers "F.Cu" "F.Mask" "F.Paste")
			(net "GND")
		)
		(pad "CH72" smd circle
			(at 31.809944 19.800062 180)
			(size 0.450088 0.450088)
			(layers "F.Cu" "F.Mask" "F.Paste")
			(net "M_A_CPU0_SB_DQ<7>")
		)
		(pad "CH73" smd circle
			(at 32.749998 19.800062 180)
			(size 0.450088 0.450088)
			(layers "F.Cu" "F.Mask" "F.Paste")
			(net "GND")
		)
		(pad "CH74" smd circle
			(at 33.690052 19.800062 180)
			(size 0.450088 0.450088)
			(layers "F.Cu" "F.Mask" "F.Paste")
			(net "M_A_CPU0_SB_DQ<8>")
		)
		(pad "CJ1" smd circle
			(at -34.459926 20.610068 180)
			(size 0.450088 0.450088)
			(layers "F.Cu" "F.Mask" "F.Paste")
			(net "GND")
		)
		(pad "CJ2" smd circle
			(at -33.519872 20.610068 180)
			(size 0.450088 0.450088)
			(layers "F.Cu" "F.Mask" "F.Paste")
			(net "M_G_CPU0_SB_DQ<10>")
		)
		(pad "CJ3" smd circle
			(at -32.580072 20.610068 180)
			(size 0.450088 0.450088)
			(layers "F.Cu" "F.Mask" "F.Paste")
			(net "M_G_CPU0_SB_DQ<9>")
		)
		(pad "CJ4" smd circle
			(at -31.640018 20.610068 180)
			(size 0.450088 0.450088)
			(layers "F.Cu" "F.Mask" "F.Paste")
			(net "GND")
		)
		(pad "CJ5" smd circle
			(at -30.699964 20.610068 180)
			(size 0.450088 0.450088)
			(layers "F.Cu" "F.Mask" "F.Paste")
			(net "M_K_CPU0_SB_DQ<10>")
		)
		(pad "CJ6" smd circle
			(at -29.75991 20.610068 180)
			(size 0.450088 0.450088)
			(layers "F.Cu" "F.Mask" "F.Paste")
			(net "GND")
		)
		(pad "CJ7" smd circle
			(at -28.82011 20.610068 180)
			(size 0.450088 0.450088)
			(layers "F.Cu" "F.Mask" "F.Paste")
			(net "M_K_CPU0_SB_DQ<9>")
		)
		(pad "CJ8" smd circle
			(at -27.880056 20.610068 180)
			(size 0.450088 0.450088)
			(layers "F.Cu" "F.Mask" "F.Paste")
			(net "GND")
		)
		(pad "CJ9" smd circle
			(at -26.940002 20.610068 180)
			(size 0.450088 0.450088)
			(layers "F.Cu" "F.Mask" "F.Paste")
			(net "M_L_CPU0_SB_DQ<10>")
		)
		(pad "CJ10" smd circle
			(at -25.999948 20.610068 180)
			(size 0.450088 0.450088)
			(layers "F.Cu" "F.Mask" "F.Paste")
			(net "M_L_CPU0_SB_DQ<9>")
		)
		(pad "CJ11" smd circle
			(at -25.059894 20.610068 180)
			(size 0.450088 0.450088)
			(layers "F.Cu" "F.Mask" "F.Paste")
			(net "GND")
		)
		(pad "CJ12" smd circle
			(at -24.120094 20.610068 180)
			(size 0.450088 0.450088)
			(layers "F.Cu" "F.Mask" "F.Paste")
			(net "M_H_CPU0_SB_DQ<10>")
		)
		(pad "CJ13" smd circle
			(at -23.18004 20.610068 180)
			(size 0.450088 0.450088)
			(layers "F.Cu" "F.Mask" "F.Paste")
			(net "GND")
		)
		(pad "CJ14" smd circle
			(at -22.239986 20.610068 180)
			(size 0.450088 0.450088)
			(layers "F.Cu" "F.Mask" "F.Paste")
			(net "M_H_CPU0_SB_DQ<9>")
		)
		(pad "CJ15" smd circle
			(at -21.299932 20.610068 180)
			(size 0.450088 0.450088)
			(layers "F.Cu" "F.Mask" "F.Paste")
			(net "GND")
		)
		(pad "CJ16" smd circle
			(at -20.359878 20.610068 180)
			(size 0.450088 0.450088)
			(layers "F.Cu" "F.Mask" "F.Paste")
			(net "M_J_CPU0_SB_DQ<10>")
		)
		(pad "CJ17" smd circle
			(at -19.420078 20.610068 180)
			(size 0.450088 0.450088)
			(layers "F.Cu" "F.Mask" "F.Paste")
			(net "M_J_CPU0_SB_DQ<9>")
		)
		(pad "CJ18" smd circle
			(at -18.480024 20.610068 180)
			(size 0.450088 0.450088)
			(layers "F.Cu" "F.Mask" "F.Paste")
			(net "GND")
		)
		(pad "CJ19" smd circle
			(at -17.53997 20.610068 180)
			(size 0.450088 0.450088)
			(layers "F.Cu" "F.Mask" "F.Paste")
			(net "M_I_CPU0_SB_DQ<10>")
		)
		(pad "CJ20" smd circle
			(at -16.599916 20.610068 180)
			(size 0.450088 0.450088)
			(layers "F.Cu" "F.Mask" "F.Paste")
			(net "GND")
		)
		(pad "CJ21" smd circle
			(at -15.660116 20.610068 180)
			(size 0.450088 0.450088)
			(layers "F.Cu" "F.Mask" "F.Paste")
			(net "M_I_CPU0_SB_DQ<9>")
		)
		(pad "CJ22" smd circle
			(at -14.720062 20.610068 180)
			(size 0.450088 0.450088)
			(layers "F.Cu" "F.Mask" "F.Paste")
			(net "PVDD11_S3_P0")
		)
		(pad "CJ23" smd circle
			(at -13.780008 20.610068 180)
			(size 0.450088 0.450088)
			(layers "F.Cu" "F.Mask" "F.Paste")
			(net "GND")
		)
		(pad "CJ24" smd circle
			(at -12.839954 20.610068 180)
			(size 0.450088 0.450088)
			(layers "F.Cu" "F.Mask" "F.Paste")
			(net "TP_CPU0_TEST47_CCD1")
		)
		(pad "CJ25" smd circle
			(at -11.8999 20.610068 180)
			(size 0.450088 0.450088)
			(layers "F.Cu" "F.Mask" "F.Paste")
			(net "TP_CPU0_TEST5_CCD5")
		)
		(pad "CJ26" smd circle
			(at -10.9601 20.610068 180)
			(size 0.450088 0.450088)
			(layers "F.Cu" "F.Mask" "F.Paste")
			(net "TP_CPU0_TEST4_CCD5")
		)
		(pad "CJ27" smd circle
			(at -10.020046 20.610068 180)
			(size 0.450088 0.450088)
			(layers "F.Cu" "F.Mask" "F.Paste")
			(net "TP_CPU0_TEST5_CCD1")
		)
		(pad "CJ28" smd circle
			(at -9.079992 20.610068 180)
			(size 0.450088 0.450088)
			(layers "F.Cu" "F.Mask" "F.Paste")
			(net "TP_CPU0_TEST4_CCD1")
		)
		(pad "CJ29" smd circle
			(at -8.139938 20.610068 180)
			(size 0.450088 0.450088)
			(layers "F.Cu" "F.Mask" "F.Paste")
			(net "TP_CPU0_TEST6_X3D1")
		)
		(pad "CJ30" smd circle
			(at -7.199884 20.610068 180)
			(size 0.450088 0.450088)
			(layers "F.Cu" "F.Mask" "F.Paste")
			(net "TP_CPU0_TEST6_CCD1")
		)
		(pad "CJ31" smd circle
			(at -6.260084 20.610068 180)
			(size 0.450088 0.450088)
			(layers "F.Cu" "F.Mask" "F.Paste")
			(net "GND")
		)
		(pad "CJ32" smd circle
			(at -5.32003 20.610068 180)
			(size 0.450088 0.450088)
			(layers "F.Cu" "F.Mask" "F.Paste")
			(net "P5E_CPU0_P3_TX_DN<4>")
		)
		(pad "CJ33" smd circle
			(at -4.379976 20.610068 180)
			(size 0.450088 0.450088)
			(layers "F.Cu" "F.Mask" "F.Paste")
			(net "P5E_CPU0_P3_TX_DP<4>")
		)
		(pad "CJ34" smd circle
			(at -3.439922 20.610068 180)
			(size 0.450088 0.450088)
			(layers "F.Cu" "F.Mask" "F.Paste")
			(net "GND")
		)
		(pad "CJ35" smd circle
			(at -2.500122 20.610068 180)
			(size 0.450088 0.450088)
			(layers "F.Cu" "F.Mask" "F.Paste")
			(net "GND")
		)
		(pad "CJ36" smd circle
			(at -1.560068 20.610068 180)
			(size 0.450088 0.450088)
			(layers "F.Cu" "F.Mask" "F.Paste")
			(net "GND")
		)
		(pad "CJ40" smd circle
			(at 1.260094 20.610068 180)
			(size 0.450088 0.450088)
			(layers "F.Cu" "F.Mask" "F.Paste")
			(net "GND")
		)
		(pad "CJ41" smd circle
			(at 2.199894 20.610068 180)
			(size 0.450088 0.450088)
			(layers "F.Cu" "F.Mask" "F.Paste")
			(net "GND")
		)
		(pad "CJ42" smd circle
			(at 3.139948 20.610068 180)
			(size 0.450088 0.450088)
			(layers "F.Cu" "F.Mask" "F.Paste")
			(net "GND")
		)
		(pad "CJ43" smd circle
			(at 4.080002 20.610068 180)
			(size 0.450088 0.450088)
			(layers "F.Cu" "F.Mask" "F.Paste")
			(net "P5E_CPU0_P1_RX_DP<11>")
		)
		(pad "CJ44" smd circle
			(at 5.020056 20.610068 180)
			(size 0.450088 0.450088)
			(layers "F.Cu" "F.Mask" "F.Paste")
			(net "P5E_CPU0_P1_RX_DN<11>")
		)
		(pad "CJ45" smd circle
			(at 5.96011 20.610068 180)
			(size 0.450088 0.450088)
			(layers "F.Cu" "F.Mask" "F.Paste")
			(net "GND")
		)
		(pad "CJ46" smd circle
			(at 6.89991 20.610068 180)
			(size 0.450088 0.450088)
			(layers "F.Cu" "F.Mask" "F.Paste")
			(net "TP_CPU0_TEST6_CCD2")
		)
		(pad "CJ47" smd circle
			(at 7.839964 20.610068 180)
			(size 0.450088 0.450088)
			(layers "F.Cu" "F.Mask" "F.Paste")
			(net "TP_CPU0_TEST4_CCD10")
		)
		(pad "CJ48" smd circle
			(at 8.780018 20.610068 180)
			(size 0.450088 0.450088)
			(layers "F.Cu" "F.Mask" "F.Paste")
			(net "TP_CPU0_TEST4_CCD2")
		)
		(pad "CJ49" smd circle
			(at 9.720072 20.610068 180)
			(size 0.450088 0.450088)
			(layers "F.Cu" "F.Mask" "F.Paste")
			(net "TP_CPU0_TEST5_CCD2")
		)
		(pad "CJ50" smd circle
			(at 10.659872 20.610068 180)
			(size 0.450088 0.450088)
			(layers "F.Cu" "F.Mask" "F.Paste")
			(net "TP_CPU0_TEST4_CCD6")
		)
		(pad "CJ51" smd circle
			(at 11.599926 20.610068 180)
			(size 0.450088 0.450088)
			(layers "F.Cu" "F.Mask" "F.Paste")
			(net "TP_CPU0_TEST5_CCD6")
		)
		(pad "CJ52" smd circle
			(at 12.53998 20.610068 180)
			(size 0.450088 0.450088)
			(layers "F.Cu" "F.Mask" "F.Paste")
			(net "TP_CPU0_TEST6_X3D3")
		)
		(pad "CJ53" smd circle
			(at 13.480034 20.610068 180)
			(size 0.450088 0.450088)
			(layers "F.Cu" "F.Mask" "F.Paste")
			(net "TP_CPU0_TEST6_X3D5")
		)
		(pad "CJ54" smd circle
			(at 14.420088 20.610068 180)
			(size 0.450088 0.450088)
			(layers "F.Cu" "F.Mask" "F.Paste")
			(net "PVDDIO_P0")
		)
		(pad "CJ55" smd circle
			(at 15.359888 20.610068 180)
			(size 0.450088 0.450088)
			(layers "F.Cu" "F.Mask" "F.Paste")
			(net "M_C_CPU0_SB_DQ<9>")
		)
		(pad "CJ56" smd circle
			(at 16.299942 20.610068 180)
			(size 0.450088 0.450088)
			(layers "F.Cu" "F.Mask" "F.Paste")
			(net "GND")
		)
		(pad "CJ57" smd circle
			(at 17.239996 20.610068 180)
			(size 0.450088 0.450088)
			(layers "F.Cu" "F.Mask" "F.Paste")
			(net "M_C_CPU0_SB_DQ<10>")
		)
		(pad "CJ58" smd circle
			(at 18.18005 20.610068 180)
			(size 0.450088 0.450088)
			(layers "F.Cu" "F.Mask" "F.Paste")
			(net "GND")
		)
		(pad "CJ59" smd circle
			(at 19.120104 20.610068 180)
			(size 0.450088 0.450088)
			(layers "F.Cu" "F.Mask" "F.Paste")
			(net "M_D_CPU0_SB_DQ<9>")
		)
		(pad "CJ60" smd circle
			(at 20.059904 20.610068 180)
			(size 0.450088 0.450088)
			(layers "F.Cu" "F.Mask" "F.Paste")
			(net "M_D_CPU0_SB_DQ<10>")
		)
		(pad "CJ61" smd circle
			(at 20.999958 20.610068 180)
			(size 0.450088 0.450088)
			(layers "F.Cu" "F.Mask" "F.Paste")
			(net "GND")
		)
		(pad "CJ62" smd circle
			(at 21.940012 20.610068 180)
			(size 0.450088 0.450088)
			(layers "F.Cu" "F.Mask" "F.Paste")
			(net "M_B_CPU0_SB_DQ<9>")
		)
	)
)
